(kicad_pcb
	(version 20260206)
	(generator "pcbnew")
	(generator_version "10.0")
	(general
		(thickness 1.6)
		(legacy_teardrops no)
	)
	(paper "A4")
	(title_block
		(title "01162023_DA0F0TEBIF0_F0T_Expander_BD_F_brd_V02_OCP.brd")
		(comment 1 "Grand Teton / footprints 6210-6215 of 9728")
	)
	(layers
		(0 "F.Cu" signal "TOP")
		(4 "In1.Cu" signal "GND")
		(6 "In2.Cu" signal "VCC")
		(8 "In3.Cu" signal "VCC1")
		(10 "In4.Cu" signal "GND1")
		(12 "In5.Cu" signal "IN1")
		(14 "In6.Cu" signal "GND2")
		(16 "In7.Cu" signal "IN2")
		(18 "In8.Cu" signal "GND3")
		(20 "In9.Cu" signal "IN3")
		(22 "In10.Cu" signal "GND4")
		(24 "In11.Cu" signal "IN4")
		(26 "In12.Cu" signal "GND5")
		(28 "In13.Cu" signal "IN5")
		(30 "In14.Cu" signal "GND6")
		(32 "In15.Cu" signal "IN6")
		(34 "In16.Cu" signal "GND7")
		(2 "B.Cu" signal "BOTTOM")
		(9 "F.Adhes" user "F.Adhesive")
		(11 "B.Adhes" user "B.Adhesive")
		(13 "F.Paste" user "Package Geometry/Pastemask Top")
		(15 "B.Paste" user "Package Geometry/Pastemask Bottom")
		(5 "F.SilkS" user "Ref Des/Silkscreen Top")
		(7 "B.SilkS" user "Ref Des/Silkscreen Bottom")
		(1 "F.Mask" user "Board Geometry/Soldermask Top")
		(3 "B.Mask" user "Board Geometry/Soldermask Bottom")
		(17 "Dwgs.User" user "User.Drawings")
		(19 "Cmts.User" user "User.Comments")
		(21 "Eco1.User" user "User.Eco1")
		(23 "Eco2.User" user "User.Eco2")
		(25 "Edge.Cuts" user "Board Geometry/Outline")
		(27 "Margin" user)
		(31 "F.CrtYd" user "Package Geometry/Place Bound Top")
		(29 "B.CrtYd" user "Package Geometry/Place Bound Bottom")
		(35 "F.Fab" user "Ref Des/Assembly Top")
		(33 "B.Fab" user "Ref Des/Assembly Bottom")
	)
	(footprint ""
		(layer "F.Cu")
		(at 72.7202 -226.673156 90)
		(property "Reference" "R6637"
			(at 0 0 90)
			(layer "F.SilkS")
			(hide yes)
			(effects
				(font
					(size 1.27 1.27)
				)
			)
		)
		(property "Value" ""
			(at 0 0 90)
			(layer "F.Fab")
			(effects
				(font
					(size 1.27 1.27)
				)
			)
		)
		(duplicate_pad_numbers_are_jumpers no)
		(fp_line
			(start 0.7874 -0.4064)
			(end 0.7874 0.4064)
			(stroke
				(width 0.1524)
				(type default)
			)
			(layer "F.SilkS")
		)
		(fp_line
			(start -0.7874 -0.4064)
			(end 0.7874 -0.4064)
			(stroke
				(width 0.1524)
				(type default)
			)
			(layer "F.SilkS")
		)
		(fp_line
			(start 0.7874 0.4064)
			(end -0.7874 0.4064)
			(stroke
				(width 0.1524)
				(type default)
			)
			(layer "F.SilkS")
		)
		(fp_line
			(start -0.7874 0.4064)
			(end -0.7874 -0.4064)
			(stroke
				(width 0.1524)
				(type default)
			)
			(layer "F.SilkS")
		)
		(fp_line
			(start -0.12065 -0.305054)
			(end -0.12065 -0.2794)
			(stroke
				(width 0.1)
				(type default)
			)
			(layer "F.Fab")
		)
		(fp_line
			(start -0.67945 -0.305054)
			(end -0.12065 -0.305054)
			(stroke
				(width 0.1)
				(type default)
			)
			(layer "F.Fab")
		)
		(fp_line
			(start 0.67945 -0.3048)
			(end 0.67945 0.3048)
			(stroke
				(width 0.1)
				(type default)
			)
			(layer "F.Fab")
		)
		(fp_line
			(start 0.12065 -0.3048)
			(end 0.67945 -0.3048)
			(stroke
				(width 0.1)
				(type default)
			)
			(layer "F.Fab")
		)
		(fp_line
			(start 0.12065 -0.2794)
			(end 0.12065 -0.3048)
			(stroke
				(width 0.1)
				(type default)
			)
			(layer "F.Fab")
		)
		(fp_line
			(start -0.12065 -0.2794)
			(end 0.12065 -0.2794)
			(stroke
				(width 0.1)
				(type default)
			)
			(layer "F.Fab")
		)
		(fp_line
			(start 0.120396 0.2794)
			(end -0.12065 0.2794)
			(stroke
				(width 0.1)
				(type default)
			)
			(layer "F.Fab")
		)
		(fp_line
			(start -0.12065 0.2794)
			(end -0.12065 0.3048)
			(stroke
				(width 0.1)
				(type default)
			)
			(layer "F.Fab")
		)
		(fp_line
			(start 0.67945 0.3048)
			(end 0.120396 0.3048)
			(stroke
				(width 0.1)
				(type default)
			)
			(layer "F.Fab")
		)
		(fp_line
			(start 0.120396 0.3048)
			(end 0.120396 0.2794)
			(stroke
				(width 0.1)
				(type default)
			)
			(layer "F.Fab")
		)
		(fp_line
			(start -0.12065 0.3048)
			(end -0.67945 0.3048)
			(stroke
				(width 0.1)
				(type default)
			)
			(layer "F.Fab")
		)
		(fp_line
			(start -0.67945 0.3048)
			(end -0.67945 -0.305054)
			(stroke
				(width 0.1)
				(type default)
			)
			(layer "F.Fab")
		)
		(pad "1" smd circle
			(at -0.40005 0 90)
			(size 0 0)
			(layers "F.Cu" "F.Mask" "F.Paste")
			(net "UART_PEX1_CLI_R_RX")
		)
		(pad "2" smd circle
			(at 0.40005 0 90)
			(size 0 0)
			(layers "F.Cu" "F.Mask" "F.Paste")
			(net "UART_PEX1_CLI_R1_RX")
		)
	)
	(footprint ""
		(layer "F.Cu")
		(at 334.01 -245.237 90)
		(property "Reference" "R1800"
			(at 0 0 90)
			(layer "F.SilkS")
			(hide yes)
			(effects
				(font
					(size 1.27 1.27)
				)
			)
		)
		(property "Value" ""
			(at 0 0 90)
			(layer "F.Fab")
			(effects
				(font
					(size 1.27 1.27)
				)
			)
		)
		(duplicate_pad_numbers_are_jumpers no)
		(fp_line
			(start 0.7874 -0.4064)
			(end 0.7874 0.4064)
			(stroke
				(width 0.1524)
				(type default)
			)
			(layer "F.SilkS")
		)
		(fp_line
			(start -0.7874 -0.4064)
			(end 0.7874 -0.4064)
			(stroke
				(width 0.1524)
				(type default)
			)
			(layer "F.SilkS")
		)
		(fp_line
			(start 0.7874 0.4064)
			(end -0.7874 0.4064)
			(stroke
				(width 0.1524)
				(type default)
			)
			(layer "F.SilkS")
		)
		(fp_line
			(start -0.7874 0.4064)
			(end -0.7874 -0.4064)
			(stroke
				(width 0.1524)
				(type default)
			)
			(layer "F.SilkS")
		)
		(fp_line
			(start -0.12065 -0.305054)
			(end -0.12065 -0.2794)
			(stroke
				(width 0.1)
				(type default)
			)
			(layer "F.Fab")
		)
		(fp_line
			(start -0.67945 -0.305054)
			(end -0.12065 -0.305054)
			(stroke
				(width 0.1)
				(type default)
			)
			(layer "F.Fab")
		)
		(fp_line
			(start 0.67945 -0.3048)
			(end 0.67945 0.3048)
			(stroke
				(width 0.1)
				(type default)
			)
			(layer "F.Fab")
		)
		(fp_line
			(start 0.12065 -0.3048)
			(end 0.67945 -0.3048)
			(stroke
				(width 0.1)
				(type default)
			)
			(layer "F.Fab")
		)
		(fp_line
			(start 0.12065 -0.2794)
			(end 0.12065 -0.3048)
			(stroke
				(width 0.1)
				(type default)
			)
			(layer "F.Fab")
		)
		(fp_line
			(start -0.12065 -0.2794)
			(end 0.12065 -0.2794)
			(stroke
				(width 0.1)
				(type default)
			)
			(layer "F.Fab")
		)
		(fp_line
			(start 0.120396 0.2794)
			(end -0.12065 0.2794)
			(stroke
				(width 0.1)
				(type default)
			)
			(layer "F.Fab")
		)
		(fp_line
			(start -0.12065 0.2794)
			(end -0.12065 0.3048)
			(stroke
				(width 0.1)
				(type default)
			)
			(layer "F.Fab")
		)
		(fp_line
			(start 0.67945 0.3048)
			(end 0.120396 0.3048)
			(stroke
				(width 0.1)
				(type default)
			)
			(layer "F.Fab")
		)
		(fp_line
			(start 0.120396 0.3048)
			(end 0.120396 0.2794)
			(stroke
				(width 0.1)
				(type default)
			)
			(layer "F.Fab")
		)
		(fp_line
			(start -0.12065 0.3048)
			(end -0.67945 0.3048)
			(stroke
				(width 0.1)
				(type default)
			)
			(layer "F.Fab")
		)
		(fp_line
			(start -0.67945 0.3048)
			(end -0.67945 -0.305054)
			(stroke
				(width 0.1)
				(type default)
			)
			(layer "F.Fab")
		)
		(pad "1" smd circle
			(at -0.40005 0 90)
			(size 0 0)
			(layers "F.Cu" "F.Mask" "F.Paste")
			(net "MB_SWB_PWRGD_BUF")
		)
		(pad "2" smd circle
			(at 0.40005 0 90)
			(size 0 0)
			(layers "F.Cu" "F.Mask" "F.Paste")
			(net "MB_SWB_PWRGD_BUF_R")
		)
	)
	(footprint ""
		(layer "F.Cu")
		(at 330.857098 -102.088442)
		(property "Reference" "PC322"
			(at 0 0 0)
			(layer "F.SilkS")
			(hide yes)
			(effects
				(font
					(size 1.27 1.27)
				)
			)
		)
		(property "Value" ""
			(at 0 0 0)
			(layer "F.Fab")
			(effects
				(font
					(size 1.27 1.27)
				)
			)
		)
		(duplicate_pad_numbers_are_jumpers no)
		(fp_line
			(start -0.7874 -0.4064)
			(end 0.7874 -0.4064)
			(stroke
				(width 0.1524)
				(type default)
			)
			(layer "F.SilkS")
		)
		(fp_line
			(start -0.7874 0.4064)
			(end -0.7874 -0.4064)
			(stroke
				(width 0.1524)
				(type default)
			)
			(layer "F.SilkS")
		)
		(fp_line
			(start 0.7874 -0.4064)
			(end 0.7874 0.4064)
			(stroke
				(width 0.1524)
				(type default)
			)
			(layer "F.SilkS")
		)
		(fp_line
			(start 0.7874 0.4064)
			(end -0.7874 0.4064)
			(stroke
				(width 0.1524)
				(type default)
			)
			(layer "F.SilkS")
		)
		(fp_line
			(start -0.67945 -0.305054)
			(end -0.12065 -0.305054)
			(stroke
				(width 0.1)
				(type default)
			)
			(layer "F.Fab")
		)
		(fp_line
			(start -0.67945 0.3048)
			(end -0.67945 -0.305054)
			(stroke
				(width 0.1)
				(type default)
			)
			(layer "F.Fab")
		)
		(fp_line
			(start -0.12065 -0.305054)
			(end -0.12065 -0.2794)
			(stroke
				(width 0.1)
				(type default)
			)
			(layer "F.Fab")
		)
		(fp_line
			(start -0.12065 -0.2794)
			(end 0.12065 -0.2794)
			(stroke
				(width 0.1)
				(type default)
			)
			(layer "F.Fab")
		)
		(fp_line
			(start -0.12065 0.2794)
			(end -0.12065 0.3048)
			(stroke
				(width 0.1)
				(type default)
			)
			(layer "F.Fab")
		)
		(fp_line
			(start -0.12065 0.3048)
			(end -0.67945 0.3048)
			(stroke
				(width 0.1)
				(type default)
			)
			(layer "F.Fab")
		)
		(fp_line
			(start 0.120396 0.2794)
			(end -0.12065 0.2794)
			(stroke
				(width 0.1)
				(type default)
			)
			(layer "F.Fab")
		)
		(fp_line
			(start 0.120396 0.3048)
			(end 0.120396 0.2794)
			(stroke
				(width 0.1)
				(type default)
			)
			(layer "F.Fab")
		)
		(fp_line
			(start 0.12065 -0.3048)
			(end 0.67945 -0.3048)
			(stroke
				(width 0.1)
				(type default)
			)
			(layer "F.Fab")
		)
		(fp_line
			(start 0.12065 -0.2794)
			(end 0.12065 -0.3048)
			(stroke
				(width 0.1)
				(type default)
			)
			(layer "F.Fab")
		)
		(fp_line
			(start 0.67945 -0.3048)
			(end 0.67945 0.3048)
			(stroke
				(width 0.1)
				(type default)
			)
			(layer "F.Fab")
		)
		(fp_line
			(start 0.67945 0.3048)
			(end 0.120396 0.3048)
			(stroke
				(width 0.1)
				(type default)
			)
			(layer "F.Fab")
		)
		(pad "1" smd circle
			(at -0.40005 0)
			(size 0 0)
			(layers "F.Cu" "F.Mask" "F.Paste")
			(net "P12V_NIC5_R")
		)
		(pad "2" smd circle
			(at 0.40005 0)
			(size 0 0)
			(layers "F.Cu" "F.Mask" "F.Paste")
			(net "GND")
		)
	)
	(footprint ""
		(layer "F.Cu")
		(at 101.829362 -384.805174 -90)
		(property "Reference" "R6727"
			(at 0 0 270)
			(layer "F.SilkS")
			(hide yes)
			(effects
				(font
					(size 1.27 1.27)
				)
			)
		)
		(property "Value" ""
			(at 0 0 270)
			(layer "F.Fab")
			(effects
				(font
					(size 1.27 1.27)
				)
			)
		)
		(duplicate_pad_numbers_are_jumpers no)
		(fp_line
			(start -0.7874 0.4064)
			(end -0.7874 -0.4064)
			(stroke
				(width 0.1524)
				(type default)
			)
			(layer "F.SilkS")
		)
		(fp_line
			(start 0.7874 0.4064)
			(end -0.017018 0.4064)
			(stroke
				(width 0.1524)
				(type default)
			)
			(layer "F.SilkS")
		)
		(fp_line
			(start -0.7874 -0.4064)
			(end 0.7874 -0.4064)
			(stroke
				(width 0.1524)
				(type default)
			)
			(layer "F.SilkS")
		)
		(fp_line
			(start -0.67945 0.3048)
			(end -0.67945 -0.305054)
			(stroke
				(width 0.1)
				(type default)
			)
			(layer "F.Fab")
		)
		(fp_line
			(start -0.12065 0.3048)
			(end -0.67945 0.3048)
			(stroke
				(width 0.1)
				(type default)
			)
			(layer "F.Fab")
		)
		(fp_line
			(start 0.120396 0.3048)
			(end 0.120396 0.2794)
			(stroke
				(width 0.1)
				(type default)
			)
			(layer "F.Fab")
		)
		(fp_line
			(start 0.67945 0.3048)
			(end 0.120396 0.3048)
			(stroke
				(width 0.1)
				(type default)
			)
			(layer "F.Fab")
		)
		(fp_line
			(start -0.12065 0.2794)
			(end -0.12065 0.3048)
			(stroke
				(width 0.1)
				(type default)
			)
			(layer "F.Fab")
		)
		(fp_line
			(start 0.120396 0.2794)
			(end -0.12065 0.2794)
			(stroke
				(width 0.1)
				(type default)
			)
			(layer "F.Fab")
		)
		(fp_line
			(start -0.12065 -0.2794)
			(end 0.12065 -0.2794)
			(stroke
				(width 0.1)
				(type default)
			)
			(layer "F.Fab")
		)
		(fp_line
			(start 0.12065 -0.2794)
			(end 0.12065 -0.3048)
			(stroke
				(width 0.1)
				(type default)
			)
			(layer "F.Fab")
		)
		(fp_line
			(start 0.12065 -0.3048)
			(end 0.67945 -0.3048)
			(stroke
				(width 0.1)
				(type default)
			)
			(layer "F.Fab")
		)
		(fp_line
			(start 0.67945 -0.3048)
			(end 0.67945 0.3048)
			(stroke
				(width 0.1)
				(type default)
			)
			(layer "F.Fab")
		)
		(fp_line
			(start -0.67945 -0.305054)
			(end -0.12065 -0.305054)
			(stroke
				(width 0.1)
				(type default)
			)
			(layer "F.Fab")
		)
		(fp_line
			(start -0.12065 -0.305054)
			(end -0.12065 -0.2794)
			(stroke
				(width 0.1)
				(type default)
			)
			(layer "F.Fab")
		)
		(pad "1" smd rect
			(at -0.40005 0 90)
			(size 0.4572 0.508)
			(layers "F.Cu" "F.Mask" "F.Paste")
			(net "USB2_MB_BMC_DP")
		)
		(pad "2" smd rect
			(at 0.40005 0 90)
			(size 0.4572 0.508)
			(layers "F.Cu" "F.Mask" "F.Paste")
			(net "USB2_MB_BMC_USB8042_DP")
		)
	)
	(footprint ""
		(layer "F.Cu")
		(at 45.498512 -66.32194 -90)
		(property "Reference" "PC640"
			(at 0 0 270)
			(layer "F.SilkS")
			(hide yes)
			(effects
				(font
					(size 1.27 1.27)
				)
			)
		)
		(property "Value" ""
			(at 0 0 270)
			(layer "F.Fab")
			(effects
				(font
					(size 1.27 1.27)
				)
			)
		)
		(duplicate_pad_numbers_are_jumpers no)
		(fp_line
			(start -0.7874 0.4064)
			(end -0.7874 -0.4064)
			(stroke
				(width 0.1524)
				(type default)
			)
			(layer "F.SilkS")
		)
		(fp_line
			(start 0.7874 0.4064)
			(end -0.7874 0.4064)
			(stroke
				(width 0.1524)
				(type default)
			)
			(layer "F.SilkS")
		)
		(fp_line
			(start -0.7874 -0.4064)
			(end 0.7874 -0.4064)
			(stroke
				(width 0.1524)
				(type default)
			)
			(layer "F.SilkS")
		)
		(fp_line
			(start 0.7874 -0.4064)
			(end 0.7874 0.4064)
			(stroke
				(width 0.1524)
				(type default)
			)
			(layer "F.SilkS")
		)
		(fp_line
			(start -0.67945 0.3048)
			(end -0.67945 -0.305054)
			(stroke
				(width 0.1)
				(type default)
			)
			(layer "F.Fab")
		)
		(fp_line
			(start -0.12065 0.3048)
			(end -0.67945 0.3048)
			(stroke
				(width 0.1)
				(type default)
			)
			(layer "F.Fab")
		)
		(fp_line
			(start 0.120396 0.3048)
			(end 0.120396 0.2794)
			(stroke
				(width 0.1)
				(type default)
			)
			(layer "F.Fab")
		)
		(fp_line
			(start 0.67945 0.3048)
			(end 0.120396 0.3048)
			(stroke
				(width 0.1)
				(type default)
			)
			(layer "F.Fab")
		)
		(fp_line
			(start -0.12065 0.2794)
			(end -0.12065 0.3048)
			(stroke
				(width 0.1)
				(type default)
			)
			(layer "F.Fab")
		)
		(fp_line
			(start 0.120396 0.2794)
			(end -0.12065 0.2794)
			(stroke
				(width 0.1)
				(type default)
			)
			(layer "F.Fab")
		)
		(fp_line
			(start -0.12065 -0.2794)
			(end 0.12065 -0.2794)
			(stroke
				(width 0.1)
				(type default)
			)
			(layer "F.Fab")
		)
		(fp_line
			(start 0.12065 -0.2794)
			(end 0.12065 -0.3048)
			(stroke
				(width 0.1)
				(type default)
			)
			(layer "F.Fab")
		)
		(fp_line
			(start 0.12065 -0.3048)
			(end 0.67945 -0.3048)
			(stroke
				(width 0.1)
				(type default)
			)
			(layer "F.Fab")
		)
		(fp_line
			(start 0.67945 -0.3048)
			(end 0.67945 0.3048)
			(stroke
				(width 0.1)
				(type default)
			)
			(layer "F.Fab")
		)
		(fp_line
			(start -0.67945 -0.305054)
			(end -0.12065 -0.305054)
			(stroke
				(width 0.1)
				(type default)
			)
			(layer "F.Fab")
		)
		(fp_line
			(start -0.12065 -0.305054)
			(end -0.12065 -0.2794)
			(stroke
				(width 0.1)
				(type default)
			)
			(layer "F.Fab")
		)
		(pad "1" smd circle
			(at -0.40005 0 270)
			(size 0 0)
			(layers "F.Cu" "F.Mask" "F.Paste")
			(net "P12V_SSD1_CO_GATE")
		)
		(pad "2" smd circle
			(at 0.40005 0 270)
			(size 0 0)
			(layers "F.Cu" "F.Mask" "F.Paste")
			(net "GND")
		)
	)
	(footprint ""
		(layer "F.Cu")
		(at 105.744772 -92.366846 90)
		(property "Reference" "R1133"
			(at 0 0 90)
			(layer "F.SilkS")
			(hide yes)
			(effects
				(font
					(size 1.27 1.27)
				)
			)
		)
		(property "Value" ""
			(at 0 0 90)
			(layer "F.Fab")
			(effects
				(font
					(size 1.27 1.27)
				)
			)
		)
		(duplicate_pad_numbers_are_jumpers no)
		(fp_line
			(start 0.7874 -0.4064)
			(end 0.7874 0.4064)
			(stroke
				(width 0.1524)
				(type default)
			)
			(layer "F.SilkS")
		)
		(fp_line
			(start -0.7874 -0.4064)
			(end 0.7874 -0.4064)
			(stroke
				(width 0.1524)
				(type default)
			)
			(layer "F.SilkS")
		)
		(fp_line
			(start 0.7874 0.4064)
			(end -0.7874 0.4064)
			(stroke
				(width 0.1524)
				(type default)
			)
			(layer "F.SilkS")
		)
		(fp_line
			(start -0.7874 0.4064)
			(end -0.7874 -0.4064)
			(stroke
				(width 0.1524)
				(type default)
			)
			(layer "F.SilkS")
		)
		(fp_line
			(start -0.12065 -0.305054)
			(end -0.12065 -0.2794)
			(stroke
				(width 0.1)
				(type default)
			)
			(layer "F.Fab")
		)
		(fp_line
			(start -0.67945 -0.305054)
			(end -0.12065 -0.305054)
			(stroke
				(width 0.1)
				(type default)
			)
			(layer "F.Fab")
		)
		(fp_line
			(start 0.67945 -0.3048)
			(end 0.67945 0.3048)
			(stroke
				(width 0.1)
				(type default)
			)
			(layer "F.Fab")
		)
		(fp_line
			(start 0.12065 -0.3048)
			(end 0.67945 -0.3048)
			(stroke
				(width 0.1)
				(type default)
			)
			(layer "F.Fab")
		)
		(fp_line
			(start 0.12065 -0.2794)
			(end 0.12065 -0.3048)
			(stroke
				(width 0.1)
				(type default)
			)
			(layer "F.Fab")
		)
		(fp_line
			(start -0.12065 -0.2794)
			(end 0.12065 -0.2794)
			(stroke
				(width 0.1)
				(type default)
			)
			(layer "F.Fab")
		)
		(fp_line
			(start 0.120396 0.2794)
			(end -0.12065 0.2794)
			(stroke
				(width 0.1)
				(type default)
			)
			(layer "F.Fab")
		)
		(fp_line
			(start -0.12065 0.2794)
			(end -0.12065 0.3048)
			(stroke
				(width 0.1)
				(type default)
			)
			(layer "F.Fab")
		)
		(fp_line
			(start 0.67945 0.3048)
			(end 0.120396 0.3048)
			(stroke
				(width 0.1)
				(type default)
			)
			(layer "F.Fab")
		)
		(fp_line
			(start 0.120396 0.3048)
			(end 0.120396 0.2794)
			(stroke
				(width 0.1)
				(type default)
			)
			(layer "F.Fab")
		)
		(fp_line
			(start -0.12065 0.3048)
			(end -0.67945 0.3048)
			(stroke
				(width 0.1)
				(type default)
			)
			(layer "F.Fab")
		)
		(fp_line
			(start -0.67945 0.3048)
			(end -0.67945 -0.305054)
			(stroke
				(width 0.1)
				(type default)
			)
			(layer "F.Fab")
		)
		(pad "1" smd circle
			(at -0.40005 0 90)
			(size 0 0)
			(layers "F.Cu" "F.Mask" "F.Paste")
			(net "PU_9ZXL0851_0_7_HBW")
		)
		(pad "2" smd circle
			(at 0.40005 0 90)
			(size 0 0)
			(layers "F.Cu" "F.Mask" "F.Paste")
			(net "GND")
		)
	)
)
